# T6G (Grand Teton) — schematic netlist excerpt (pin names and nets, part order shuffled) for the footprints in the layout excerpt that follows; sources: Cadence DE-HDL packaged netlist, KiCad conversion of 04192023_DAF0TMB3IC0_F0TG_MB_C_brd_V02_OCP.brd

C195  Q_CAP  4.7UF 6.3V 20% X6S  pkg 0402  page 334 : A = P1V8_CPU1_RT1_1A ; B = GND
C365  Q_CAP  0.1UF 10V 10% X7S  pkg C0201  page 185 : A = P1V8_AUX ; B = GND
R307  Q_RES  1K 1% CHIP  pkg 0402LF  page 102 : A = PWRGD_CHE_CPU1_DIMM ; B = PWRGD_CHAF_CPU1

(kicad_pcb
	(version 20260206)
	(generator "pcbnew")
	(generator_version "10.0")
	(general
		(thickness 1.6)
		(legacy_teardrops no)
	)
	(paper "A4")
	(title_block
		(title "04192023_DAF0TMB3IC0_F0TG_MB_C_brd_V02_OCP.brd")
		(comment 1 "Grand Teton / footprints 4947-4949 of 8354")
	)
	(layers
		(0 "F.Cu" signal "TOP")
		(4 "In1.Cu" signal "GND")
		(6 "In2.Cu" signal "IN1")
		(8 "In3.Cu" signal "GND1")
		(10 "In4.Cu" signal "IN2")
		(12 "In5.Cu" signal "GND2")
		(14 "In6.Cu" signal "IN3")
		(16 "In7.Cu" signal "GND3")
		(18 "In8.Cu" signal "VCC")
		(20 "In9.Cu" signal "VCC1")
		(22 "In10.Cu" signal "GND4")
		(24 "In11.Cu" signal "IN4")
		(26 "In12.Cu" signal "GND5")
		(28 "In13.Cu" signal "IN5")
		(30 "In14.Cu" signal "GND6")
		(32 "In15.Cu" signal "IN6")
		(34 "In16.Cu" signal "GND7")
		(2 "B.Cu" signal "BOTTOM")
		(9 "F.Adhes" user "F.Adhesive")
		(11 "B.Adhes" user "B.Adhesive")
		(13 "F.Paste" user "Package Geometry/Pastemask Top")
		(15 "B.Paste" user "Package Geometry/Pastemask Bottom")
		(5 "F.SilkS" user "Ref Des/Silkscreen Top")
		(7 "B.SilkS" user "Ref Des/Silkscreen Bottom")
		(1 "F.Mask" user "Board Geometry/Soldermask Top")
		(3 "B.Mask" user "Board Geometry/Soldermask Bottom")
		(17 "Dwgs.User" user "User.Drawings")
		(19 "Cmts.User" user "User.Comments")
		(21 "Eco1.User" user "User.Eco1")
		(23 "Eco2.User" user "User.Eco2")
		(25 "Edge.Cuts" user "Board Geometry/Outline")
		(27 "Margin" user)
		(31 "F.CrtYd" user "Package Geometry/Place Bound Top")
		(29 "B.CrtYd" user "Package Geometry/Place Bound Bottom")
		(35 "F.Fab" user "Ref Des/Assembly Top")
		(33 "B.Fab" user "Ref Des/Assembly Bottom")
	)
	(footprint ""
		(layer "B.Cu")
		(at 88.319102 -390.560052 90)
		(property "Reference" "C195"
			(at 0 0 90)
			(layer "B.SilkS")
			(hide yes)
			(effects
				(font
					(size 1.27 1.27)
				)
				(justify mirror)
			)
		)
		(property "Value" ""
			(at 0 0 90)
			(layer "B.Fab")
			(effects
				(font
					(size 1.27 1.27)
				)
				(justify mirror)
			)
		)
		(duplicate_pad_numbers_are_jumpers no)
		(fp_line
			(start 0.7874 -0.4064)
			(end -0.7874 -0.4064)
			(stroke
				(width 0.1524)
				(type default)
			)
			(layer "B.SilkS")
		)
		(fp_line
			(start -0.7874 -0.4064)
			(end -0.7874 0.4064)
			(stroke
				(width 0.1524)
				(type default)
			)
			(layer "B.SilkS")
		)
		(fp_line
			(start 0.7874 0.4064)
			(end 0.7874 -0.4064)
			(stroke
				(width 0.1524)
				(type default)
			)
			(layer "B.SilkS")
		)
		(fp_line
			(start -0.7874 0.4064)
			(end 0.7874 0.4064)
			(stroke
				(width 0.1524)
				(type default)
			)
			(layer "B.SilkS")
		)
		(fp_line
			(start 0.67945 -0.305054)
			(end 0.12065 -0.305054)
			(stroke
				(width 0.1)
				(type default)
			)
			(layer "B.Fab")
		)
		(fp_line
			(start 0.12065 -0.305054)
			(end 0.12065 -0.2794)
			(stroke
				(width 0.1)
				(type default)
			)
			(layer "B.Fab")
		)
		(fp_line
			(start -0.12065 -0.3048)
			(end -0.67945 -0.3048)
			(stroke
				(width 0.1)
				(type default)
			)
			(layer "B.Fab")
		)
		(fp_line
			(start -0.67945 -0.3048)
			(end -0.67945 0.3048)
			(stroke
				(width 0.1)
				(type default)
			)
			(layer "B.Fab")
		)
		(fp_line
			(start 0.12065 -0.2794)
			(end -0.12065 -0.2794)
			(stroke
				(width 0.1)
				(type default)
			)
			(layer "B.Fab")
		)
		(fp_line
			(start -0.12065 -0.2794)
			(end -0.12065 -0.3048)
			(stroke
				(width 0.1)
				(type default)
			)
			(layer "B.Fab")
		)
		(fp_line
			(start 0.12065 0.2794)
			(end 0.12065 0.3048)
			(stroke
				(width 0.1)
				(type default)
			)
			(layer "B.Fab")
		)
		(fp_line
			(start -0.120396 0.2794)
			(end 0.12065 0.2794)
			(stroke
				(width 0.1)
				(type default)
			)
			(layer "B.Fab")
		)
		(fp_line
			(start 0.67945 0.3048)
			(end 0.67945 -0.305054)
			(stroke
				(width 0.1)
				(type default)
			)
			(layer "B.Fab")
		)
		(fp_line
			(start 0.12065 0.3048)
			(end 0.67945 0.3048)
			(stroke
				(width 0.1)
				(type default)
			)
			(layer "B.Fab")
		)
		(fp_line
			(start -0.120396 0.3048)
			(end -0.120396 0.2794)
			(stroke
				(width 0.1)
				(type default)
			)
			(layer "B.Fab")
		)
		(fp_line
			(start -0.67945 0.3048)
			(end -0.120396 0.3048)
			(stroke
				(width 0.1)
				(type default)
			)
			(layer "B.Fab")
		)
		(pad "1" smd circle
			(at 0.40005 0 270)
			(size 0 0)
			(layers "B.Cu" "B.Mask" "B.Paste")
			(net "P1V8_CPU1_RT1_1A")
		)
		(pad "2" smd circle
			(at -0.40005 0 270)
			(size 0 0)
			(layers "B.Cu" "B.Mask" "B.Paste")
			(net "GND")
		)
	)
	(footprint ""
		(layer "B.Cu")
		(at 25.313386 -190.948564 180)
		(property "Reference" "R307"
			(at 0 0 0)
			(layer "B.SilkS")
			(hide yes)
			(effects
				(font
					(size 1.27 1.27)
				)
				(justify mirror)
			)
		)
		(property "Value" ""
			(at 0 0 0)
			(layer "B.Fab")
			(effects
				(font
					(size 1.27 1.27)
				)
				(justify mirror)
			)
		)
		(duplicate_pad_numbers_are_jumpers no)
		(fp_line
			(start 0.7874 0.4064)
			(end 0.7874 -0.4064)
			(stroke
				(width 0.1524)
				(type default)
			)
			(layer "B.SilkS")
		)
		(fp_line
			(start 0.7874 -0.4064)
			(end -0.7874 -0.4064)
			(stroke
				(width 0.1524)
				(type default)
			)
			(layer "B.SilkS")
		)
		(fp_line
			(start -0.7874 0.4064)
			(end 0.7874 0.4064)
			(stroke
				(width 0.1524)
				(type default)
			)
			(layer "B.SilkS")
		)
		(fp_line
			(start -0.7874 -0.4064)
			(end -0.7874 0.4064)
			(stroke
				(width 0.1524)
				(type default)
			)
			(layer "B.SilkS")
		)
		(fp_line
			(start 0.67945 0.3048)
			(end 0.67945 -0.305054)
			(stroke
				(width 0.1)
				(type default)
			)
			(layer "B.Fab")
		)
		(fp_line
			(start 0.67945 -0.305054)
			(end 0.12065 -0.305054)
			(stroke
				(width 0.1)
				(type default)
			)
			(layer "B.Fab")
		)
		(fp_line
			(start 0.12065 0.3048)
			(end 0.67945 0.3048)
			(stroke
				(width 0.1)
				(type default)
			)
			(layer "B.Fab")
		)
		(fp_line
			(start 0.12065 0.2794)
			(end 0.12065 0.3048)
			(stroke
				(width 0.1)
				(type default)
			)
			(layer "B.Fab")
		)
		(fp_line
			(start 0.12065 -0.2794)
			(end -0.12065 -0.2794)
			(stroke
				(width 0.1)
				(type default)
			)
			(layer "B.Fab")
		)
		(fp_line
			(start 0.12065 -0.305054)
			(end 0.12065 -0.2794)
			(stroke
				(width 0.1)
				(type default)
			)
			(layer "B.Fab")
		)
		(fp_line
			(start -0.120396 0.3048)
			(end -0.120396 0.2794)
			(stroke
				(width 0.1)
				(type default)
			)
			(layer "B.Fab")
		)
		(fp_line
			(start -0.120396 0.2794)
			(end 0.12065 0.2794)
			(stroke
				(width 0.1)
				(type default)
			)
			(layer "B.Fab")
		)
		(fp_line
			(start -0.12065 -0.2794)
			(end -0.12065 -0.3048)
			(stroke
				(width 0.1)
				(type default)
			)
			(layer "B.Fab")
		)
		(fp_line
			(start -0.12065 -0.3048)
			(end -0.67945 -0.3048)
			(stroke
				(width 0.1)
				(type default)
			)
			(layer "B.Fab")
		)
		(fp_line
			(start -0.67945 0.3048)
			(end -0.120396 0.3048)
			(stroke
				(width 0.1)
				(type default)
			)
			(layer "B.Fab")
		)
		(fp_line
			(start -0.67945 -0.3048)
			(end -0.67945 0.3048)
			(stroke
				(width 0.1)
				(type default)
			)
			(layer "B.Fab")
		)
		(pad "1" smd circle
			(at 0.40005 0)
			(size 0 0)
			(layers "B.Cu" "B.Mask" "B.Paste")
			(net "PWRGD_CHE_CPU1_DIMM")
		)
		(pad "2" smd circle
			(at -0.40005 0)
			(size 0 0)
			(layers "B.Cu" "B.Mask" "B.Paste")
			(net "PWRGD_CHAF_CPU1")
		)
	)
	(footprint ""
		(layer "B.Cu")
		(at 248.539 -332.105)
		(property "Reference" "C365"
			(at 0 0 0)
			(layer "B.SilkS")
			(hide yes)
			(effects
				(font
					(size 1.27 1.27)
				)
				(justify mirror)
			)
		)
		(property "Value" ""
			(at 0 0 0)
			(layer "B.Fab")
			(effects
				(font
					(size 1.27 1.27)
				)
				(justify mirror)
			)
		)
		(duplicate_pad_numbers_are_jumpers no)
		(fp_line
			(start -0.299974 -0.150114)
			(end -0.299974 0.150114)
			(stroke
				(width 0.1)
				(type default)
			)
			(layer "B.Fab")
		)
		(fp_line
			(start -0.299974 0.150114)
			(end 0.299974 0.150114)
			(stroke
				(width 0.1)
				(type default)
			)
			(layer "B.Fab")
		)
		(fp_line
			(start 0.299974 -0.150114)
			(end -0.299974 -0.150114)
			(stroke
				(width 0.1)
				(type default)
			)
			(layer "B.Fab")
		)
		(fp_line
			(start 0.299974 0.150114)
			(end 0.299974 -0.150114)
			(stroke
				(width 0.1)
				(type default)
			)
			(layer "B.Fab")
		)
		(pad "1" smd rect
			(at 0.2667 0 180)
			(size 0.3048 0.381)
			(layers "B.Cu" "B.Mask" "B.Paste")
			(net "P1V8_AUX")
		)
		(pad "2" smd rect
			(at -0.2667 0 180)
			(size 0.3048 0.381)
			(layers "B.Cu" "B.Mask" "B.Paste")
			(net "GND")
		)
	)
)
